# S9S_MB_2U (Grand Teton) — schematic netlist excerpt (pin names and nets, part order shuffled) for the footprints in the layout excerpt that follows; sources: Cadence DE-HDL packaged netlist, KiCad conversion of 03242023_DA0F0TMBIJ0_F0T_Motherboard_J_brd_V01_OCP.brd

U29  PCA9617ADP  IC  pkg TSSOP8_3XB  page 235
  VCCA  = PVNN_TERM_CPU1
  SCLA  = SMB_PEHPCPU1_GTL_R_SCL
  SDAA  = SMB_PEHPCPU1_GTL_R_SDA
  GND  = GND
  EN  = TP_SMB_PEHPCPU1_EN
  SDAB  = SMB_PEHPCPU1_LVC3_SDA_R0
  SCLB  = SMB_PEHPCPU1_LVC3_SCL_R0
  VCCB  = P3V3_AUX

R4516  Q_RES  10K 1% CHIP  pkg 0402LF  page 206 : A = P3V3 ; B = CLK_SWB_OE_N

(kicad_pcb
	(version 20260206)
	(generator "pcbnew")
	(generator_version "10.0")
	(general
		(thickness 1.6)
		(legacy_teardrops no)
	)
	(paper "A4")
	(title_block
		(title "03242023_DA0F0TMBIJ0_F0T_Motherboard_J_brd_V01_OCP.brd")
		(comment 1 "Grand Teton / footprints 5716-5717 of 6105")
	)
	(layers
		(0 "F.Cu" signal "TOP")
		(4 "In1.Cu" signal "GND")
		(6 "In2.Cu" signal "IN1")
		(8 "In3.Cu" signal "GND1")
		(10 "In4.Cu" signal "IN2")
		(12 "In5.Cu" signal "GND2")
		(14 "In6.Cu" signal "IN3")
		(16 "In7.Cu" signal "GND3")
		(18 "In8.Cu" signal "VCC")
		(20 "In9.Cu" signal "VCC1")
		(22 "In10.Cu" signal "GND4")
		(24 "In11.Cu" signal "IN4")
		(26 "In12.Cu" signal "GND5")
		(28 "In13.Cu" signal "IN5")
		(30 "In14.Cu" signal "GND6")
		(32 "In15.Cu" signal "IN6")
		(34 "In16.Cu" signal "GND7")
		(2 "B.Cu" signal "BOTTOM")
		(9 "F.Adhes" user "F.Adhesive")
		(11 "B.Adhes" user "B.Adhesive")
		(13 "F.Paste" user "Package Geometry/Pastemask Top")
		(15 "B.Paste" user "Package Geometry/Pastemask Bottom")
		(5 "F.SilkS" user "Ref Des/Silkscreen Top")
		(7 "B.SilkS" user "Ref Des/Silkscreen Bottom")
		(1 "F.Mask" user "Board Geometry/Soldermask Top")
		(3 "B.Mask" user "Board Geometry/Soldermask Bottom")
		(17 "Dwgs.User" user "User.Drawings")
		(19 "Cmts.User" user "User.Comments")
		(21 "Eco1.User" user "User.Eco1")
		(23 "Eco2.User" user "User.Eco2")
		(25 "Edge.Cuts" user "Board Geometry/Outline")
		(27 "Margin" user)
		(31 "F.CrtYd" user "Package Geometry/Place Bound Top")
		(29 "B.CrtYd" user "Package Geometry/Place Bound Bottom")
		(35 "F.Fab" user "Ref Des/Assembly Top")
		(33 "B.Fab" user "Ref Des/Assembly Bottom")
	)
	(footprint ""
		(layer "B.Cu")
		(at 11.756136 -192.774824)
		(property "Reference" "U29"
			(at 1.6891 -2.880868 0)
			(unlocked yes)
			(layer "B.SilkS")
			(effects
				(font
					(size 0.7874 0.5842)
					(thickness 0.1524)
				)
				(justify left mirror)
			)
		)
		(property "Value" ""
			(at 0 0 0)
			(layer "B.Fab")
			(effects
				(font
					(size 1.27 1.27)
				)
				(justify mirror)
			)
		)
		(duplicate_pad_numbers_are_jumpers no)
		(fp_line
			(start -1.463548 -1.549908)
			(end -1.463548 1.549908)
			(stroke
				(width 0.1524)
				(type default)
			)
			(layer "B.SilkS")
		)
		(fp_line
			(start -1.463548 1.549908)
			(end 1.463548 1.549908)
			(stroke
				(width 0.1524)
				(type default)
			)
			(layer "B.SilkS")
		)
		(fp_line
			(start -0.762 -1.549908)
			(end -1.463548 -1.549908)
			(stroke
				(width 0.1524)
				(type default)
			)
			(layer "B.SilkS")
		)
		(fp_line
			(start 0 -0.762)
			(end -0.762 -1.549908)
			(stroke
				(width 0.1524)
				(type default)
			)
			(layer "B.SilkS")
		)
		(fp_line
			(start 0.787908 -1.549908)
			(end 0 -0.762)
			(stroke
				(width 0.1524)
				(type default)
			)
			(layer "B.SilkS")
		)
		(fp_line
			(start 1.463548 -1.549908)
			(end 0.787908 -1.549908)
			(stroke
				(width 0.1524)
				(type default)
			)
			(layer "B.SilkS")
		)
		(fp_line
			(start 1.463548 1.549908)
			(end 1.463548 -1.549908)
			(stroke
				(width 0.1524)
				(type default)
			)
			(layer "B.SilkS")
		)
		(fp_poly
			(pts
				(xy 3.4798 -1.359916) (xy 3.4798 -0.740156) (xy 2.86004 -1.050036)
			)
			(stroke
				(width 0)
				(type default)
			)
			(fill yes)
			(layer "B.SilkS")
		)
		(fp_line
			(start -1.549908 -1.549908)
			(end -1.549908 1.549908)
			(stroke
				(width 0.1)
				(type default)
			)
			(layer "B.Fab")
		)
		(fp_line
			(start -1.549908 1.549908)
			(end 1.549908 1.549908)
			(stroke
				(width 0.1)
				(type default)
			)
			(layer "B.Fab")
		)
		(fp_line
			(start 1.549908 -1.549908)
			(end -1.549908 -1.549908)
			(stroke
				(width 0.1)
				(type default)
			)
			(layer "B.Fab")
		)
		(fp_line
			(start 1.549908 1.549908)
			(end 1.549908 -1.549908)
			(stroke
				(width 0.1)
				(type default)
			)
			(layer "B.Fab")
		)
		(fp_poly
			(pts
				(xy 3.4798 -1.359916) (xy 2.86004 -1.050036) (xy 3.4798 -0.740156)
			)
			(stroke
				(width 0)
				(type default)
			)
			(fill yes)
			(layer "B.Fab")
		)
		(pad "1" smd rect
			(at 2.175002 -1.050036 90)
			(size 0.6096 1.1684)
			(layers "B.Cu" "B.Mask" "B.Paste")
			(net "PVNN_TERM_CPU1")
		)
		(pad "2" smd rect
			(at 2.175002 -0.32512 90)
			(size 0.4318 1.1684)
			(layers "B.Cu" "B.Mask" "B.Paste")
			(net "SMB_PEHPCPU1_GTL_R_SCL")
		)
		(pad "3" smd rect
			(at 2.175002 0.32512 90)
			(size 0.4318 1.1684)
			(layers "B.Cu" "B.Mask" "B.Paste")
			(net "SMB_PEHPCPU1_GTL_R_SDA")
		)
		(pad "4" smd rect
			(at 2.175002 1.050036 90)
			(size 0.6096 1.1684)
			(layers "B.Cu" "B.Mask" "B.Paste")
			(net "GND")
		)
		(pad "5" smd rect
			(at -2.175002 1.050036 90)
			(size 0.6096 1.1684)
			(layers "B.Cu" "B.Mask" "B.Paste")
			(net "TP_SMB_PEHPCPU1_EN")
		)
		(pad "6" smd rect
			(at -2.175002 0.32512 90)
			(size 0.4318 1.1684)
			(layers "B.Cu" "B.Mask" "B.Paste")
			(net "SMB_PEHPCPU1_LVC3_SDA_R0")
		)
		(pad "7" smd rect
			(at -2.175002 -0.32512 90)
			(size 0.4318 1.1684)
			(layers "B.Cu" "B.Mask" "B.Paste")
			(net "SMB_PEHPCPU1_LVC3_SCL_R0")
		)
		(pad "8" smd rect
			(at -2.175002 -1.050036 90)
			(size 0.6096 1.1684)
			(layers "B.Cu" "B.Mask" "B.Paste")
			(net "P3V3_AUX")
		)
	)
	(footprint ""
		(layer "B.Cu")
		(at 227.071174 -128.74625 180)
		(property "Reference" "R4516"
			(at 0 0 0)
			(layer "B.SilkS")
			(hide yes)
			(effects
				(font
					(size 1.27 1.27)
				)
				(justify mirror)
			)
		)
		(property "Value" ""
			(at 0 0 0)
			(layer "B.Fab")
			(effects
				(font
					(size 1.27 1.27)
				)
				(justify mirror)
			)
		)
		(duplicate_pad_numbers_are_jumpers no)
		(fp_line
			(start 0.7874 0.4064)
			(end 0.7874 -0.4064)
			(stroke
				(width 0.1524)
				(type default)
			)
			(layer "B.SilkS")
		)
		(fp_line
			(start 0.7874 -0.4064)
			(end -0.7874 -0.4064)
			(stroke
				(width 0.1524)
				(type default)
			)
			(layer "B.SilkS")
		)
		(fp_line
			(start -0.7874 0.4064)
			(end 0.7874 0.4064)
			(stroke
				(width 0.1524)
				(type default)
			)
			(layer "B.SilkS")
		)
		(fp_line
			(start -0.7874 -0.4064)
			(end -0.7874 0.4064)
			(stroke
				(width 0.1524)
				(type default)
			)
			(layer "B.SilkS")
		)
		(fp_line
			(start 0.67945 0.3048)
			(end 0.67945 -0.305054)
			(stroke
				(width 0.1)
				(type default)
			)
			(layer "B.Fab")
		)
		(fp_line
			(start 0.67945 -0.305054)
			(end 0.12065 -0.305054)
			(stroke
				(width 0.1)
				(type default)
			)
			(layer "B.Fab")
		)
		(fp_line
			(start 0.12065 0.3048)
			(end 0.67945 0.3048)
			(stroke
				(width 0.1)
				(type default)
			)
			(layer "B.Fab")
		)
		(fp_line
			(start 0.12065 0.2794)
			(end 0.12065 0.3048)
			(stroke
				(width 0.1)
				(type default)
			)
			(layer "B.Fab")
		)
		(fp_line
			(start 0.12065 -0.2794)
			(end -0.12065 -0.2794)
			(stroke
				(width 0.1)
				(type default)
			)
			(layer "B.Fab")
		)
		(fp_line
			(start 0.12065 -0.305054)
			(end 0.12065 -0.2794)
			(stroke
				(width 0.1)
				(type default)
			)
			(layer "B.Fab")
		)
		(fp_line
			(start -0.120396 0.3048)
			(end -0.120396 0.2794)
			(stroke
				(width 0.1)
				(type default)
			)
			(layer "B.Fab")
		)
		(fp_line
			(start -0.120396 0.2794)
			(end 0.12065 0.2794)
			(stroke
				(width 0.1)
				(type default)
			)
			(layer "B.Fab")
		)
		(fp_line
			(start -0.12065 -0.2794)
			(end -0.12065 -0.3048)
			(stroke
				(width 0.1)
				(type default)
			)
			(layer "B.Fab")
		)
		(fp_line
			(start -0.12065 -0.3048)
			(end -0.67945 -0.3048)
			(stroke
				(width 0.1)
				(type default)
			)
			(layer "B.Fab")
		)
		(fp_line
			(start -0.67945 0.3048)
			(end -0.120396 0.3048)
			(stroke
				(width 0.1)
				(type default)
			)
			(layer "B.Fab")
		)
		(fp_line
			(start -0.67945 -0.3048)
			(end -0.67945 0.3048)
			(stroke
				(width 0.1)
				(type default)
			)
			(layer "B.Fab")
		)
		(pad "1" smd circle
			(at 0.40005 0)
			(size 0 0)
			(layers "B.Cu" "B.Mask" "B.Paste")
			(net "P3V3")
		)
		(pad "2" smd circle
			(at -0.40005 0)
			(size 0 0)
			(layers "B.Cu" "B.Mask" "B.Paste")
			(net "CLK_SWB_OE_N")
		)
	)
)
